# SCM (Grand Teton) — schematic netlist excerpt (pin names and nets, part order shuffled) for the footprints in the layout excerpt that follows; sources: Cadence DE-HDL packaged netlist, KiCad conversion of 12092022_DA0F0TMDCD0_F0T_Management_Board_D_brd_V3_OCP.brd

R832  Q_RES  12K 1% CHIP  pkg 0402LF  page 54 : A = U41_ADJ ; B = GND
PR521  Q_RES  681K 1% CHIP  pkg 0402LF  page 51 : A = P12V_AUX ; B = EN_P5V_AUX

(kicad_pcb
	(version 20260206)
	(generator "pcbnew")
	(generator_version "10.0")
	(general
		(thickness 1.6)
		(legacy_teardrops no)
	)
	(paper "A4")
	(title_block
		(title "12092022_DA0F0TMDCD0_F0T_Management_Board_D_brd_V3_OCP.brd")
		(comment 1 "Grand Teton / footprints 681-682 of 1440")
	)
	(layers
		(0 "F.Cu" signal "TOP")
		(4 "In1.Cu" signal "GND")
		(6 "In2.Cu" signal "IN1")
		(8 "In3.Cu" signal "GND1")
		(10 "In4.Cu" signal "IN2")
		(12 "In5.Cu" signal "VCC")
		(14 "In6.Cu" signal "VCC1")
		(16 "In7.Cu" signal "IN3")
		(18 "In8.Cu" signal "GND2")
		(20 "In9.Cu" signal "IN4")
		(22 "In10.Cu" signal "GND3")
		(2 "B.Cu" signal "BOTTOM")
		(9 "F.Adhes" user "F.Adhesive")
		(11 "B.Adhes" user "B.Adhesive")
		(13 "F.Paste" user "Package Geometry/Pastemask Top")
		(15 "B.Paste" user "Package Geometry/Pastemask Bottom")
		(5 "F.SilkS" user "Ref Des/Silkscreen Top")
		(7 "B.SilkS" user "Ref Des/Silkscreen Bottom")
		(1 "F.Mask" user "Board Geometry/Soldermask Top")
		(3 "B.Mask" user "Board Geometry/Soldermask Bottom")
		(17 "Dwgs.User" user "User.Drawings")
		(19 "Cmts.User" user "User.Comments")
		(21 "Eco1.User" user "User.Eco1")
		(23 "Eco2.User" user "User.Eco2")
		(25 "Edge.Cuts" user "Board Geometry/Outline")
		(27 "Margin" user)
		(31 "F.CrtYd" user "Package Geometry/Place Bound Top")
		(29 "B.CrtYd" user "Package Geometry/Place Bound Bottom")
		(35 "F.Fab" user "Ref Des/Assembly Top")
		(33 "B.Fab" user "Ref Des/Assembly Bottom")
	)
	(footprint ""
		(layer "F.Cu")
		(at 13.169646 -52.008532 -90)
		(property "Reference" "PR521"
			(at 0 0 270)
			(layer "F.SilkS")
			(hide yes)
			(effects
				(font
					(size 1.27 1.27)
				)
			)
		)
		(property "Value" ""
			(at 0 0 270)
			(layer "F.Fab")
			(effects
				(font
					(size 1.27 1.27)
				)
			)
		)
		(duplicate_pad_numbers_are_jumpers no)
		(fp_line
			(start -0.7874 0.4064)
			(end -0.7874 -0.4064)
			(stroke
				(width 0.1524)
				(type default)
			)
			(layer "F.SilkS")
		)
		(fp_line
			(start 0.7874 0.4064)
			(end -0.7874 0.4064)
			(stroke
				(width 0.1524)
				(type default)
			)
			(layer "F.SilkS")
		)
		(fp_line
			(start -0.7874 -0.4064)
			(end 0.7874 -0.4064)
			(stroke
				(width 0.1524)
				(type default)
			)
			(layer "F.SilkS")
		)
		(fp_line
			(start 0.7874 -0.4064)
			(end 0.7874 0.4064)
			(stroke
				(width 0.1524)
				(type default)
			)
			(layer "F.SilkS")
		)
		(fp_line
			(start -0.67945 0.3048)
			(end -0.67945 -0.305054)
			(stroke
				(width 0.1)
				(type default)
			)
			(layer "F.Fab")
		)
		(fp_line
			(start -0.12065 0.3048)
			(end -0.67945 0.3048)
			(stroke
				(width 0.1)
				(type default)
			)
			(layer "F.Fab")
		)
		(fp_line
			(start 0.120396 0.3048)
			(end 0.120396 0.2794)
			(stroke
				(width 0.1)
				(type default)
			)
			(layer "F.Fab")
		)
		(fp_line
			(start 0.67945 0.3048)
			(end 0.120396 0.3048)
			(stroke
				(width 0.1)
				(type default)
			)
			(layer "F.Fab")
		)
		(fp_line
			(start -0.12065 0.2794)
			(end -0.12065 0.3048)
			(stroke
				(width 0.1)
				(type default)
			)
			(layer "F.Fab")
		)
		(fp_line
			(start 0.120396 0.2794)
			(end -0.12065 0.2794)
			(stroke
				(width 0.1)
				(type default)
			)
			(layer "F.Fab")
		)
		(fp_line
			(start -0.12065 -0.2794)
			(end 0.12065 -0.2794)
			(stroke
				(width 0.1)
				(type default)
			)
			(layer "F.Fab")
		)
		(fp_line
			(start 0.12065 -0.2794)
			(end 0.12065 -0.3048)
			(stroke
				(width 0.1)
				(type default)
			)
			(layer "F.Fab")
		)
		(fp_line
			(start 0.12065 -0.3048)
			(end 0.67945 -0.3048)
			(stroke
				(width 0.1)
				(type default)
			)
			(layer "F.Fab")
		)
		(fp_line
			(start 0.67945 -0.3048)
			(end 0.67945 0.3048)
			(stroke
				(width 0.1)
				(type default)
			)
			(layer "F.Fab")
		)
		(fp_line
			(start -0.67945 -0.305054)
			(end -0.12065 -0.305054)
			(stroke
				(width 0.1)
				(type default)
			)
			(layer "F.Fab")
		)
		(fp_line
			(start -0.12065 -0.305054)
			(end -0.12065 -0.2794)
			(stroke
				(width 0.1)
				(type default)
			)
			(layer "F.Fab")
		)
		(pad "1" smd circle
			(at -0.40005 0 270)
			(size 0 0)
			(layers "F.Cu" "F.Mask" "F.Paste")
			(net "P12V_AUX")
		)
		(pad "2" smd circle
			(at 0.40005 0 270)
			(size 0 0)
			(layers "F.Cu" "F.Mask" "F.Paste")
			(net "EN_P5V_AUX")
		)
	)
	(footprint ""
		(layer "F.Cu")
		(at 40.648128 -55.427626 -90)
		(property "Reference" "R832"
			(at 0 0 270)
			(layer "F.SilkS")
			(hide yes)
			(effects
				(font
					(size 1.27 1.27)
				)
			)
		)
		(property "Value" ""
			(at 0 0 270)
			(layer "F.Fab")
			(effects
				(font
					(size 1.27 1.27)
				)
			)
		)
		(duplicate_pad_numbers_are_jumpers no)
		(fp_line
			(start -0.7874 0.4064)
			(end -0.7874 -0.4064)
			(stroke
				(width 0.1524)
				(type default)
			)
			(layer "F.SilkS")
		)
		(fp_line
			(start 0.7874 0.4064)
			(end -0.7874 0.4064)
			(stroke
				(width 0.1524)
				(type default)
			)
			(layer "F.SilkS")
		)
		(fp_line
			(start -0.7874 -0.4064)
			(end 0.7874 -0.4064)
			(stroke
				(width 0.1524)
				(type default)
			)
			(layer "F.SilkS")
		)
		(fp_line
			(start 0.7874 -0.4064)
			(end 0.7874 0.4064)
			(stroke
				(width 0.1524)
				(type default)
			)
			(layer "F.SilkS")
		)
		(fp_line
			(start -0.67945 0.3048)
			(end -0.67945 -0.305054)
			(stroke
				(width 0.1)
				(type default)
			)
			(layer "F.Fab")
		)
		(fp_line
			(start -0.12065 0.3048)
			(end -0.67945 0.3048)
			(stroke
				(width 0.1)
				(type default)
			)
			(layer "F.Fab")
		)
		(fp_line
			(start 0.120396 0.3048)
			(end 0.120396 0.2794)
			(stroke
				(width 0.1)
				(type default)
			)
			(layer "F.Fab")
		)
		(fp_line
			(start 0.67945 0.3048)
			(end 0.120396 0.3048)
			(stroke
				(width 0.1)
				(type default)
			)
			(layer "F.Fab")
		)
		(fp_line
			(start -0.12065 0.2794)
			(end -0.12065 0.3048)
			(stroke
				(width 0.1)
				(type default)
			)
			(layer "F.Fab")
		)
		(fp_line
			(start 0.120396 0.2794)
			(end -0.12065 0.2794)
			(stroke
				(width 0.1)
				(type default)
			)
			(layer "F.Fab")
		)
		(fp_line
			(start -0.12065 -0.2794)
			(end 0.12065 -0.2794)
			(stroke
				(width 0.1)
				(type default)
			)
			(layer "F.Fab")
		)
		(fp_line
			(start 0.12065 -0.2794)
			(end 0.12065 -0.3048)
			(stroke
				(width 0.1)
				(type default)
			)
			(layer "F.Fab")
		)
		(fp_line
			(start 0.12065 -0.3048)
			(end 0.67945 -0.3048)
			(stroke
				(width 0.1)
				(type default)
			)
			(layer "F.Fab")
		)
		(fp_line
			(start 0.67945 -0.3048)
			(end 0.67945 0.3048)
			(stroke
				(width 0.1)
				(type default)
			)
			(layer "F.Fab")
		)
		(fp_line
			(start -0.67945 -0.305054)
			(end -0.12065 -0.305054)
			(stroke
				(width 0.1)
				(type default)
			)
			(layer "F.Fab")
		)
		(fp_line
			(start -0.12065 -0.305054)
			(end -0.12065 -0.2794)
			(stroke
				(width 0.1)
				(type default)
			)
			(layer "F.Fab")
		)
		(pad "1" smd circle
			(at -0.40005 0 270)
			(size 0 0)
			(layers "F.Cu" "F.Mask" "F.Paste")
			(net "U41_ADJ")
		)
		(pad "2" smd circle
			(at 0.40005 0 270)
			(size 0 0)
			(layers "F.Cu" "F.Mask" "F.Paste")
			(net "GND")
		)
	)
)
